# BASEBOARD_FAB2 (Tioga Pass) — schematic netlist excerpt (pin names and nets, part order shuffled) for the footprints in the layout excerpt that follows; sources: Cadence DE-HDL packaged netlist, KiCad conversion of Wiwynn_Tioga_Pass_MB.brd

J1B1  SCONN288_H44441004  SCONN  pkg PIP  page 83
  \12v\(1)  = P12V_NVDIMM_KLM
  VSS(93)  = GND
  DQ(4)  = M_K_DQ<5>
  VSS(92)  = GND
  DQ(0)  = M_K_DQ<1>
  VSS(91)  = GND
  DQS9P  = M_K_DQS_DP<9>
  DQS9N  = M_K_DQS_DN<9>
  VSS(90)  = GND
  DQ(6)  = M_K_DQ<7>
  VSS(89)  = GND
  DQ(2)  = M_K_DQ<3>
  VSS(88)  = GND
  DQ(12)  = M_K_DQ<13>
  VSS(87)  = GND
  DQ(8)  = M_K_DQ<9>
  VSS(86)  = GND
  DQS10P  = M_K_DQS_DP<10>
  DQS10N  = M_K_DQS_DN<10>
  VSS(85)  = GND
  DQ(14)  = M_K_DQ<15>
  VSS(84)  = GND
  DQ(10)  = M_K_DQ<11>
  VSS(83)  = GND
  DQ(20)  = M_K_DQ<21>
  VSS(82)  = GND
  DQ(16)  = M_K_DQ<17>
  VSS(81)  = GND
  DQS11P  = M_K_DQS_DP<11>
  DQS11N  = M_K_DQS_DN<11>
  VSS(80)  = GND
  DQ(22)  = M_K_DQ<23>
  VSS(79)  = GND
  DQ(18)  = M_K_DQ<19>
  VSS(78)  = GND
  DQ(28)  = M_K_DQ<29>
  VSS(77)  = GND
  DQ(24)  = M_K_DQ<25>
  VSS(76)  = GND
  DQS12P  = M_K_DQS_DP<12>
  DQS12N  = M_K_DQS_DN<12>
  VSS(75)  = GND
  DQ(30)  = M_K_DQ<31>
  VSS(74)  = GND
  DQ(26)  = M_K_DQ<27>
  VSS(73)  = GND
  CB(4)  = M_K_ECC<5>
  VSS(72)  = GND
  CB(0)  = M_K_ECC<1>
  VSS(71)  = GND
  DQS17P  = M_K_DQS_DP<17>
  DQS17N  = M_K_DQS_DN<17>
  VSS(70)  = GND
  CB(6)  = M_K_ECC<7>
  VSS(69)  = GND
  CB(2)  = M_K_ECC<3>
  VSS(68)  = GND
  RESET_N  = M_KLM_RST_N
  VDD(25)  = PVDDQ_KLM
  CKE(0)  = M_K_CKE<0>
  VDD(24)  = PVDDQ_KLM
  ACT_N  = M_K_ACT_N
  BG(0)  = M_K_BG<0>
  VDD(23)  = PVDDQ_KLM
  A12  = M_K_MA<12>
  A9  = M_K_MA<9>
  VDD(22)  = PVDDQ_KLM
  A8  = M_K_MA<8>
  A6  = M_K_MA<6>
  VDD(21)  = PVDDQ_KLM
  A3  = M_K_MA<3>
  A1  = M_K_MA<1>
  VDD(20)  = PVDDQ_KLM
  CK0P  = M_K_CLK_DP<0>
  CK0N  = M_K_CLK_DN<0>
  VDD(19)  = PVDDQ_KLM
  VTT(1)  = PVTT_KLM
  EVENT_N  = FM_DIMM_EVENT_COD_N
  A0  = M_K_MA<0>
  VDD(18)  = PVDDQ_KLM
  BA(0)  = M_K_BA<0>
  A16_RAS_N  = M_K_MA<16>
  VDD(17)  = PVDDQ_KLM
  S0_N  = M_K_CS_N<0>
  VDD(16)  = PVDDQ_KLM
  A15_CAS_N  = M_K_MA<15>
  ODT(0)  = M_K_ODT<0>
  VDD(15)  = PVDDQ_KLM
  S1_N  = M_K_CS_N<1>
  VDD(14)  = PVDDQ_KLM
  ODT(1)  = M_K_ODT<1>
  VDD(13)  = PVDDQ_KLM
  S2_N_C(0)  = M_K_CS_N<2>
  VSS(67)  = GND
  DQ(36)  = M_K_DQ<37>
  VSS(66)  = GND
  DQ(32)  = M_K_DQ<33>
  VSS(65)  = GND
  DQS13P  = M_K_DQS_DP<13>
  DQS13N  = M_K_DQS_DN<13>
  VSS(64)  = GND
  DQ(38)  = M_K_DQ<39>
  VSS(63)  = GND
  DQ(34)  = M_K_DQ<35>
  VSS(62)  = GND
  DQ(44)  = M_K_DQ<45>
  VSS(61)  = GND
  DQ(40)  = M_K_DQ<41>
  VSS(60)  = GND
  DQS14P  = M_K_DQS_DP<14>
  DQS14N  = M_K_DQS_DN<14>
  VSS(59)  = GND
  DQ(46)  = M_K_DQ<47>
  VSS(58)  = GND
  DQ(42)  = M_K_DQ<43>
  VSS(57)  = GND
  DQ(52)  = M_K_DQ<53>
  VSS(56)  = GND
  DQ(48)  = M_K_DQ<49>
  VSS(55)  = GND
  DQS15P  = M_K_DQS_DP<15>
  DQS15N  = M_K_DQS_DN<15>
  VSS(54)  = GND
  DQ(54)  = M_K_DQ<55>
  VSS(53)  = GND
  DQ(50)  = M_K_DQ<51>
  VSS(52)  = GND
  DQ(60)  = M_K_DQ<61>
  VSS(51)  = GND
  DQ(56)  = M_K_DQ<57>
  VSS(50)  = GND
  DQS16P  = M_K_DQS_DP<16>
  DQS16N  = M_K_DQS_DN<16>
  VSS(49)  = GND
  DQ(62)  = M_K_DQ<63>
  VSS(48)  = GND
  DQ(58)  = M_K_DQ<59>
  VSS(47)  = GND
  SA(0)  = GND
  SA(1)  = GND
  SCL  = SMB_DDR_KLM_VPP_SCL
  VPP(4)  = PVPP_KLM
  VPP(3)  = PVPP_KLM
  RFU(2)  = TP_CH_K_DIMM_K0_RFU_2
  \12v\(0)  = P12V_NVDIMM_KLM
  VREFCA  = M_K_VREF
  VSS(46)  = GND
  DQ(5)  = M_K_DQ<4>
  VSS(45)  = GND
  DQ(1)  = M_K_DQ<0>
  VSS(44)  = GND
  DQS0N  = M_K_DQS_DN<0>
  DQS0P  = M_K_DQS_DP<0>
  VSS(43)  = GND
  DQ(7)  = M_K_DQ<6>
  VSS(42)  = GND
  DQ(3)  = M_K_DQ<2>
  VSS(41)  = GND
  DQ(13)  = M_K_DQ<12>
  VSS(40)  = GND
  DQ(9)  = M_K_DQ<8>
  VSS(39)  = GND
  DQS1N  = M_K_DQS_DN<1>
  DQS1P  = M_K_DQS_DP<1>
  VSS(38)  = GND
  DQ(15)  = M_K_DQ<14>
  VSS(37)  = GND
  DQ(11)  = M_K_DQ<10>
  VSS(36)  = GND
  DQ(21)  = M_K_DQ<20>
  VSS(35)  = GND
  DQ(17)  = M_K_DQ<16>
  VSS(34)  = GND
  DQS2N  = M_K_DQS_DN<2>
  DQS2P  = M_K_DQS_DP<2>
  VSS(33)  = GND
  DQ(23)  = M_K_DQ<22>
  VSS(32)  = GND
  DQ(19)  = M_K_DQ<18>
  VSS(31)  = GND
  DQ(29)  = M_K_DQ<28>
  VSS(30)  = GND
  DQ(25)  = M_K_DQ<24>
  VSS(29)  = GND
  DQS3N  = M_K_DQS_DN<3>
  DQS3P  = M_K_DQS_DP<3>
  VSS(28)  = GND
  DQ(31)  = M_K_DQ<30>
  VSS(27)  = GND
  DQ(27)  = M_K_DQ<26>
  VSS(26)  = GND
  CB(5)  = M_K_ECC<4>
  VSS(25)  = GND
  CB(1)  = M_K_ECC<0>
  VSS(24)  = GND
  DQS8N  = M_K_DQS_DN<8>
  DQS8P  = M_K_DQS_DP<8>
  VSS(23)  = GND
  CB(7)  = M_K_ECC<6>
  VSS(22)  = GND
  CB(3)  = M_K_ECC<2>
  VSS(21)  = GND
  CKE(1)  = M_K_CKE<1>
  VDD(12)  = PVDDQ_KLM
  RFU(0)  = TP_CH_K_DIMM_K0_RFU_0
  VDD(11)  = PVDDQ_KLM
  BG(1)  = M_K_BG<1>
  ALERT_N  = M_K_ALERT_N
  VDD(10)  = PVDDQ_KLM
  A11  = M_K_MA<11>
  A7  = M_K_MA<7>
  VDD(9)  = PVDDQ_KLM
  A5  = M_K_MA<5>
  A4  = M_K_MA<4>
  VDD(8)  = PVDDQ_KLM
  A2  = M_K_MA<2>
  VDD(7)  = PVDDQ_KLM
  CK1P  = M_K_CLK_DP<1>
  CK1N  = M_K_CLK_DN<1>
  VDD(6)  = PVDDQ_KLM
  VTT(0)  = PVTT_KLM
  PAR  = M_K_PAR
  VDD(5)  = PVDDQ_KLM
  BA(1)  = M_K_BA<1>
  A10  = M_K_MA<10>
  VDD(4)  = PVDDQ_KLM
  RFU(1)  = TP_CH_K_DIMM_K0_RFU_1
  A14_WE_N  = M_K_MA<14>
  VDD(3)  = PVDDQ_KLM
  SAVE_N_NC  = FM_ADR_COMPLETE_KLM_N
  VDD(2)  = PVDDQ_KLM
  A13  = M_K_MA<13>
  VDD(1)  = PVDDQ_KLM
  A17  = M_K_MA<17>
  C(2)  = M_K_C<2>
  VDD(0)  = PVDDQ_KLM
  S3_N_C(1)  = M_K_CS_N<3>
  SA(2)  = GND
  VSS(20)  = GND
  DQ(37)  = M_K_DQ<36>
  VSS(19)  = GND
  DQ(33)  = M_K_DQ<32>
  VSS(18)  = GND
  DQS4N  = M_K_DQS_DN<4>
  DQS4P  = M_K_DQS_DP<4>
  VSS(17)  = GND
  DQ(39)  = M_K_DQ<38>
  VSS(16)  = GND
  DQ(35)  = M_K_DQ<34>
  VSS(15)  = GND
  DQ(45)  = M_K_DQ<44>
  VSS(14)  = GND
  DQ(41)  = M_K_DQ<40>
  VSS(13)  = GND
  DQS5N  = M_K_DQS_DN<5>
  DQS5P  = M_K_DQS_DP<5>
  VSS(12)  = GND
  DQ(47)  = M_K_DQ<46>
  VSS(11)  = GND
  DQ(43)  = M_K_DQ<42>
  VSS(10)  = GND
  DQ(53)  = M_K_DQ<52>
  VSS(9)  = GND
  DQ(49)  = M_K_DQ<48>
  VSS(8)  = GND
  DQS6N  = M_K_DQS_DN<6>
  DQS6P  = M_K_DQS_DP<6>
  VSS(7)  = GND
  DQ(55)  = M_K_DQ<54>
  VSS(6)  = GND
  DQ(51)  = M_K_DQ<50>
  VSS(5)  = GND
  DQ(61)  = M_K_DQ<60>
  VSS(4)  = GND
  DQ(57)  = M_K_DQ<56>
  VSS(3)  = GND
  DQS7N  = M_K_DQS_DN<7>
  DQS7P  = M_K_DQS_DP<7>
  VSS(2)  = GND
  DQ(63)  = M_K_DQ<62>
  VSS(1)  = GND
  DQ(59)  = M_K_DQ<58>
  VSS(0)  = GND
  VDDSPD  = PVPP_KLM
  SDA  = SMB_DDR_KLM_VPP_SDA
  VPP(1)  = PVPP_KLM
  VPP(0)  = PVPP_KLM
  VPP(2)  = PVPP_KLM

(kicad_pcb
	(version 20260206)
	(generator "pcbnew")
	(generator_version "10.0")
	(general
		(thickness 1.6)
		(legacy_teardrops no)
	)
	(paper "A4")
	(title_block
		(title "Wiwynn_Tioga_Pass_MB.brd")
		(comment 1 "Tioga Pass / footprint 320 of 4770 (J1B1), pads 52-101 of 291")
	)
	(layers
		(0 "F.Cu" signal "TOP")
		(4 "In1.Cu" signal "L2GND")
		(6 "In2.Cu" signal "L3")
		(8 "In3.Cu" signal "L4GND")
		(10 "In4.Cu" signal "L5")
		(12 "In5.Cu" signal "L6GND")
		(14 "In6.Cu" signal "L7VCC")
		(16 "In7.Cu" signal "L8VCC")
		(18 "In8.Cu" signal "L9GND")
		(20 "In9.Cu" signal "L10")
		(22 "In10.Cu" signal "L11GND")
		(24 "In11.Cu" signal "L12")
		(26 "In12.Cu" signal "L13GND")
		(2 "B.Cu" signal "BOTTOM")
		(9 "F.Adhes" user "F.Adhesive")
		(11 "B.Adhes" user "B.Adhesive")
		(13 "F.Paste" user "Package Geometry/Pastemask Top")
		(15 "B.Paste" user "Package Geometry/Pastemask Bottom")
		(5 "F.SilkS" user "Ref Des/Silkscreen Top")
		(7 "B.SilkS" user "Ref Des/Silkscreen Bottom")
		(1 "F.Mask" user "Board Geometry/Soldermask Top")
		(3 "B.Mask" user "Board Geometry/Soldermask Bottom")
		(17 "Dwgs.User" user "User.Drawings")
		(19 "Cmts.User" user "User.Comments")
		(21 "Eco1.User" user "User.Eco1")
		(23 "Eco2.User" user "User.Eco2")
		(25 "Edge.Cuts" user "Board Geometry/Outline")
		(27 "Margin" user)
		(31 "F.CrtYd" user "Package Geometry/Place Bound Top")
		(29 "B.CrtYd" user "Package Geometry/Place Bound Bottom")
		(35 "F.Fab" user "Ref Des/Assembly Top")
		(33 "B.Fab" user "Ref Des/Assembly Bottom")
	)
	(footprint ""
		(layer "F.Cu")
		(at 29.699458 -133.0706 90)
		(property "Reference" "J1B1"
			(at -4.960112 38.372542 0)
			(unlocked yes)
			(layer "F.SilkS")
			(effects
				(font
					(size 0.7874 0.5842)
					(thickness 0.1524)
				)
				(justify left)
			)
		)
		(property "Value" ""
			(at 0 0 90)
			(layer "F.Fab")
			(effects
				(font
					(size 1.27 1.27)
				)
			)
		)
		(duplicate_pad_numbers_are_jumpers no)
		(pad "49" smd rect
			(at 0 40.80002 90)
			(size 1.8034 0.508)
			(layers "F.Cu" "F.Mask" "F.Paste")
			(net "M_K_ECC<1>")
		)
		(pad "50" smd rect
			(at 0 41.649904 90)
			(size 1.8034 0.508)
			(layers "F.Cu" "F.Mask" "F.Paste")
			(net "GND")
		)
		(pad "51" smd rect
			(at 0 42.500042 90)
			(size 1.8034 0.508)
			(layers "F.Cu" "F.Mask" "F.Paste")
			(net "M_K_DQS_DP<17>")
		)
		(pad "52" smd rect
			(at 0 43.349926 90)
			(size 1.8034 0.508)
			(layers "F.Cu" "F.Mask" "F.Paste")
			(net "M_K_DQS_DN<17>")
		)
		(pad "53" smd rect
			(at 0 44.200064 90)
			(size 1.8034 0.508)
			(layers "F.Cu" "F.Mask" "F.Paste")
			(net "GND")
		)
		(pad "54" smd rect
			(at 0 45.049948 90)
			(size 1.8034 0.508)
			(layers "F.Cu" "F.Mask" "F.Paste")
			(net "M_K_ECC<7>")
		)
		(pad "55" smd rect
			(at 0 45.900086 90)
			(size 1.8034 0.508)
			(layers "F.Cu" "F.Mask" "F.Paste")
			(net "GND")
		)
		(pad "56" smd rect
			(at 0 46.74997 90)
			(size 1.8034 0.508)
			(layers "F.Cu" "F.Mask" "F.Paste")
			(net "M_K_ECC<3>")
		)
		(pad "57" smd rect
			(at 0 47.600108 90)
			(size 1.8034 0.508)
			(layers "F.Cu" "F.Mask" "F.Paste")
			(net "GND")
		)
		(pad "58" smd rect
			(at 0 48.449992 90)
			(size 1.8034 0.508)
			(layers "F.Cu" "F.Mask" "F.Paste")
			(net "M_KLM_RST_N")
		)
		(pad "59" smd rect
			(at 0 49.299876 90)
			(size 1.8034 0.508)
			(layers "F.Cu" "F.Mask" "F.Paste")
			(net "PVDDQ_KLM")
		)
		(pad "60" smd rect
			(at 0 50.150014 90)
			(size 1.8034 0.508)
			(layers "F.Cu" "F.Mask" "F.Paste")
			(net "M_K_CKE<0>")
		)
		(pad "61" smd rect
			(at 0 50.999898 90)
			(size 1.8034 0.508)
			(layers "F.Cu" "F.Mask" "F.Paste")
			(net "PVDDQ_KLM")
		)
		(pad "62" smd rect
			(at 0 51.850036 90)
			(size 1.8034 0.508)
			(layers "F.Cu" "F.Mask" "F.Paste")
			(net "M_K_ACT_N")
		)
		(pad "63" smd rect
			(at 0 52.69992 90)
			(size 1.8034 0.508)
			(layers "F.Cu" "F.Mask" "F.Paste")
			(net "M_K_BG<0>")
		)
		(pad "64" smd rect
			(at 0 53.550058 90)
			(size 1.8034 0.508)
			(layers "F.Cu" "F.Mask" "F.Paste")
			(net "PVDDQ_KLM")
		)
		(pad "65" smd rect
			(at 0 54.399942 90)
			(size 1.8034 0.508)
			(layers "F.Cu" "F.Mask" "F.Paste")
			(net "M_K_MA<12>")
		)
		(pad "66" smd rect
			(at 0 55.25008 90)
			(size 1.8034 0.508)
			(layers "F.Cu" "F.Mask" "F.Paste")
			(net "M_K_MA<9>")
		)
		(pad "67" smd rect
			(at 0 56.099964 90)
			(size 1.8034 0.508)
			(layers "F.Cu" "F.Mask" "F.Paste")
			(net "PVDDQ_KLM")
		)
		(pad "68" smd rect
			(at 0 56.950102 90)
			(size 1.8034 0.508)
			(layers "F.Cu" "F.Mask" "F.Paste")
			(net "M_K_MA<8>")
		)
		(pad "69" smd rect
			(at 0 57.799986 90)
			(size 1.8034 0.508)
			(layers "F.Cu" "F.Mask" "F.Paste")
			(net "M_K_MA<6>")
		)
		(pad "70" smd rect
			(at 0 58.650124 90)
			(size 1.8034 0.508)
			(layers "F.Cu" "F.Mask" "F.Paste")
			(net "PVDDQ_KLM")
		)
		(pad "71" smd rect
			(at 0 59.500008 90)
			(size 1.8034 0.508)
			(layers "F.Cu" "F.Mask" "F.Paste")
			(net "M_K_MA<3>")
		)
		(pad "72" smd rect
			(at 0 60.349892 90)
			(size 1.8034 0.508)
			(layers "F.Cu" "F.Mask" "F.Paste")
			(net "M_K_MA<1>")
		)
		(pad "73" smd rect
			(at 0 61.20003 90)
			(size 1.8034 0.508)
			(layers "F.Cu" "F.Mask" "F.Paste")
			(net "PVDDQ_KLM")
		)
		(pad "74" smd rect
			(at 0 62.049914 90)
			(size 1.8034 0.508)
			(layers "F.Cu" "F.Mask" "F.Paste")
			(net "M_K_CLK_DP<0>")
		)
		(pad "75" smd rect
			(at 0 62.900052 90)
			(size 1.8034 0.508)
			(layers "F.Cu" "F.Mask" "F.Paste")
			(net "M_K_CLK_DN<0>")
		)
		(pad "76" smd rect
			(at 0 63.749936 90)
			(size 1.8034 0.508)
			(layers "F.Cu" "F.Mask" "F.Paste")
			(net "PVDDQ_KLM")
		)
		(pad "77" smd rect
			(at 0 64.600074 90)
			(size 1.8034 0.508)
			(layers "F.Cu" "F.Mask" "F.Paste")
			(net "PVTT_KLM")
		)
		(pad "78" smd rect
			(at 0 70.550024 90)
			(size 1.8034 0.508)
			(layers "F.Cu" "F.Mask" "F.Paste")
			(net "FM_DIMM_EVENT_COD_N")
		)
		(pad "79" smd rect
			(at 0 71.399908 90)
			(size 1.8034 0.508)
			(layers "F.Cu" "F.Mask" "F.Paste")
			(net "M_K_MA<0>")
		)
		(pad "80" smd rect
			(at 0 72.250046 90)
			(size 1.8034 0.508)
			(layers "F.Cu" "F.Mask" "F.Paste")
			(net "PVDDQ_KLM")
		)
		(pad "81" smd rect
			(at 0 73.09993 90)
			(size 1.8034 0.508)
			(layers "F.Cu" "F.Mask" "F.Paste")
			(net "M_K_BA<0>")
		)
		(pad "82" smd rect
			(at 0 73.950068 90)
			(size 1.8034 0.508)
			(layers "F.Cu" "F.Mask" "F.Paste")
			(net "M_K_MA<16>")
		)
		(pad "83" smd rect
			(at 0 74.799952 90)
			(size 1.8034 0.508)
			(layers "F.Cu" "F.Mask" "F.Paste")
			(net "PVDDQ_KLM")
		)
		(pad "84" smd rect
			(at 0 75.65009 90)
			(size 1.8034 0.508)
			(layers "F.Cu" "F.Mask" "F.Paste")
			(net "M_K_CS_N<0>")
		)
		(pad "85" smd rect
			(at 0 76.499974 90)
			(size 1.8034 0.508)
			(layers "F.Cu" "F.Mask" "F.Paste")
			(net "PVDDQ_KLM")
		)
		(pad "86" smd rect
			(at 0 77.350112 90)
			(size 1.8034 0.508)
			(layers "F.Cu" "F.Mask" "F.Paste")
			(net "M_K_MA<15>")
		)
		(pad "87" smd rect
			(at 0 78.199996 90)
			(size 1.8034 0.508)
			(layers "F.Cu" "F.Mask" "F.Paste")
			(net "M_K_ODT<0>")
		)
		(pad "88" smd rect
			(at 0 79.04988 90)
			(size 1.8034 0.508)
			(layers "F.Cu" "F.Mask" "F.Paste")
			(net "PVDDQ_KLM")
		)
		(pad "89" smd rect
			(at 0 79.900018 90)
			(size 1.8034 0.508)
			(layers "F.Cu" "F.Mask" "F.Paste")
			(net "M_K_CS_N<1>")
		)
		(pad "90" smd rect
			(at 0 80.749902 90)
			(size 1.8034 0.508)
			(layers "F.Cu" "F.Mask" "F.Paste")
			(net "PVDDQ_KLM")
		)
		(pad "91" smd rect
			(at 0 81.60004 90)
			(size 1.8034 0.508)
			(layers "F.Cu" "F.Mask" "F.Paste")
			(net "M_K_ODT<1>")
		)
		(pad "92" smd rect
			(at 0 82.449924 90)
			(size 1.8034 0.508)
			(layers "F.Cu" "F.Mask" "F.Paste")
			(net "PVDDQ_KLM")
		)
		(pad "93" smd rect
			(at 0 83.300062 90)
			(size 1.8034 0.508)
			(layers "F.Cu" "F.Mask" "F.Paste")
			(net "M_K_CS_N<2>")
		)
		(pad "94" smd rect
			(at 0 84.149946 90)
			(size 1.8034 0.508)
			(layers "F.Cu" "F.Mask" "F.Paste")
			(net "GND")
		)
		(pad "95" smd rect
			(at 0 85.000084 90)
			(size 1.8034 0.508)
			(layers "F.Cu" "F.Mask" "F.Paste")
			(net "M_K_DQ<37>")
		)
		(pad "96" smd rect
			(at 0 85.849968 90)
			(size 1.8034 0.508)
			(layers "F.Cu" "F.Mask" "F.Paste")
			(net "GND")
		)
		(pad "97" smd rect
			(at 0 86.700106 90)
			(size 1.8034 0.508)
			(layers "F.Cu" "F.Mask" "F.Paste")
			(net "M_K_DQ<33>")
		)
		(pad "98" smd rect
			(at 0 87.54999 90)
			(size 1.8034 0.508)
			(layers "F.Cu" "F.Mask" "F.Paste")
			(net "GND")
		)
	)
)
